# S9S_MB_2U (Grand Teton) — schematic netlist excerpt (pin names and nets, part order shuffled) for the footprints in the layout excerpt that follows; sources: Cadence DE-HDL packaged netlist, KiCad conversion of 03242023_DA0F0TMBIJ0_F0T_Motherboard_J_brd_V01_OCP.brd

C2358  Q_CAP  0.1UF 25V 10% X7R  pkg 0402  page 167 : A = P2E_BUF2_VDD ; B = GND
R617  Q_RES  1K 1% EMPTY  pkg 0402LF  page 199 : A = P3V3_AUX ; B = FM_PCH_IO_EXPANDER

(kicad_pcb
	(version 20260206)
	(generator "pcbnew")
	(generator_version "10.0")
	(general
		(thickness 1.6)
		(legacy_teardrops no)
	)
	(paper "A4")
	(title_block
		(title "03242023_DA0F0TMBIJ0_F0T_Motherboard_J_brd_V01_OCP.brd")
		(comment 1 "Grand Teton / footprints 1548-1549 of 6105")
	)
	(layers
		(0 "F.Cu" signal "TOP")
		(4 "In1.Cu" signal "GND")
		(6 "In2.Cu" signal "IN1")
		(8 "In3.Cu" signal "GND1")
		(10 "In4.Cu" signal "IN2")
		(12 "In5.Cu" signal "GND2")
		(14 "In6.Cu" signal "IN3")
		(16 "In7.Cu" signal "GND3")
		(18 "In8.Cu" signal "VCC")
		(20 "In9.Cu" signal "VCC1")
		(22 "In10.Cu" signal "GND4")
		(24 "In11.Cu" signal "IN4")
		(26 "In12.Cu" signal "GND5")
		(28 "In13.Cu" signal "IN5")
		(30 "In14.Cu" signal "GND6")
		(32 "In15.Cu" signal "IN6")
		(34 "In16.Cu" signal "GND7")
		(2 "B.Cu" signal "BOTTOM")
		(9 "F.Adhes" user "F.Adhesive")
		(11 "B.Adhes" user "B.Adhesive")
		(13 "F.Paste" user "Package Geometry/Pastemask Top")
		(15 "B.Paste" user "Package Geometry/Pastemask Bottom")
		(5 "F.SilkS" user "Ref Des/Silkscreen Top")
		(7 "B.SilkS" user "Ref Des/Silkscreen Bottom")
		(1 "F.Mask" user "Board Geometry/Soldermask Top")
		(3 "B.Mask" user "Board Geometry/Soldermask Bottom")
		(17 "Dwgs.User" user "User.Drawings")
		(19 "Cmts.User" user "User.Comments")
		(21 "Eco1.User" user "User.Eco1")
		(23 "Eco2.User" user "User.Eco2")
		(25 "Edge.Cuts" user "Board Geometry/Outline")
		(27 "Margin" user)
		(31 "F.CrtYd" user "Package Geometry/Place Bound Top")
		(29 "B.CrtYd" user "Package Geometry/Place Bound Bottom")
		(35 "F.Fab" user "Ref Des/Assembly Top")
		(33 "B.Fab" user "Ref Des/Assembly Bottom")
	)
	(footprint ""
		(layer "F.Cu")
		(at 320.190622 -58.283348)
		(property "Reference" "R617"
			(at 0 0 0)
			(layer "F.SilkS")
			(hide yes)
			(effects
				(font
					(size 1.27 1.27)
				)
			)
		)
		(property "Value" ""
			(at 0 0 0)
			(layer "F.Fab")
			(effects
				(font
					(size 1.27 1.27)
				)
			)
		)
		(duplicate_pad_numbers_are_jumpers no)
		(fp_line
			(start -0.7874 -0.4064)
			(end 0.7874 -0.4064)
			(stroke
				(width 0.1524)
				(type default)
			)
			(layer "F.SilkS")
		)
		(fp_line
			(start -0.7874 0.4064)
			(end -0.7874 -0.4064)
			(stroke
				(width 0.1524)
				(type default)
			)
			(layer "F.SilkS")
		)
		(fp_line
			(start 0.7874 -0.4064)
			(end 0.7874 0.4064)
			(stroke
				(width 0.1524)
				(type default)
			)
			(layer "F.SilkS")
		)
		(fp_line
			(start 0.7874 0.4064)
			(end -0.7874 0.4064)
			(stroke
				(width 0.1524)
				(type default)
			)
			(layer "F.SilkS")
		)
		(fp_line
			(start -0.67945 -0.305054)
			(end -0.12065 -0.305054)
			(stroke
				(width 0.1)
				(type default)
			)
			(layer "F.Fab")
		)
		(fp_line
			(start -0.67945 0.3048)
			(end -0.67945 -0.305054)
			(stroke
				(width 0.1)
				(type default)
			)
			(layer "F.Fab")
		)
		(fp_line
			(start -0.12065 -0.305054)
			(end -0.12065 -0.2794)
			(stroke
				(width 0.1)
				(type default)
			)
			(layer "F.Fab")
		)
		(fp_line
			(start -0.12065 -0.2794)
			(end 0.12065 -0.2794)
			(stroke
				(width 0.1)
				(type default)
			)
			(layer "F.Fab")
		)
		(fp_line
			(start -0.12065 0.2794)
			(end -0.12065 0.3048)
			(stroke
				(width 0.1)
				(type default)
			)
			(layer "F.Fab")
		)
		(fp_line
			(start -0.12065 0.3048)
			(end -0.67945 0.3048)
			(stroke
				(width 0.1)
				(type default)
			)
			(layer "F.Fab")
		)
		(fp_line
			(start 0.120396 0.2794)
			(end -0.12065 0.2794)
			(stroke
				(width 0.1)
				(type default)
			)
			(layer "F.Fab")
		)
		(fp_line
			(start 0.120396 0.3048)
			(end 0.120396 0.2794)
			(stroke
				(width 0.1)
				(type default)
			)
			(layer "F.Fab")
		)
		(fp_line
			(start 0.12065 -0.3048)
			(end 0.67945 -0.3048)
			(stroke
				(width 0.1)
				(type default)
			)
			(layer "F.Fab")
		)
		(fp_line
			(start 0.12065 -0.2794)
			(end 0.12065 -0.3048)
			(stroke
				(width 0.1)
				(type default)
			)
			(layer "F.Fab")
		)
		(fp_line
			(start 0.67945 -0.3048)
			(end 0.67945 0.3048)
			(stroke
				(width 0.1)
				(type default)
			)
			(layer "F.Fab")
		)
		(fp_line
			(start 0.67945 0.3048)
			(end 0.120396 0.3048)
			(stroke
				(width 0.1)
				(type default)
			)
			(layer "F.Fab")
		)
		(pad "1" smd circle
			(at -0.40005 0)
			(size 0 0)
			(layers "F.Cu" "F.Mask" "F.Paste")
			(net "P3V3_AUX")
		)
		(pad "2" smd circle
			(at 0.40005 0)
			(size 0 0)
			(layers "F.Cu" "F.Mask" "F.Paste")
			(net "FM_PCH_IO_EXPANDER")
		)
	)
	(footprint ""
		(layer "F.Cu")
		(at 39.263574 -387.340856 -90)
		(property "Reference" "C2358"
			(at 0 0 270)
			(layer "F.SilkS")
			(hide yes)
			(effects
				(font
					(size 1.27 1.27)
				)
			)
		)
		(property "Value" ""
			(at 0 0 270)
			(layer "F.Fab")
			(effects
				(font
					(size 1.27 1.27)
				)
			)
		)
		(duplicate_pad_numbers_are_jumpers no)
		(fp_line
			(start -0.7874 0.4064)
			(end -0.7874 -0.4064)
			(stroke
				(width 0.1524)
				(type default)
			)
			(layer "F.SilkS")
		)
		(fp_line
			(start 0.7874 0.4064)
			(end -0.7874 0.4064)
			(stroke
				(width 0.1524)
				(type default)
			)
			(layer "F.SilkS")
		)
		(fp_line
			(start -0.7874 -0.4064)
			(end 0.7874 -0.4064)
			(stroke
				(width 0.1524)
				(type default)
			)
			(layer "F.SilkS")
		)
		(fp_line
			(start 0.7874 -0.4064)
			(end 0.7874 0.4064)
			(stroke
				(width 0.1524)
				(type default)
			)
			(layer "F.SilkS")
		)
		(fp_line
			(start -0.67945 0.3048)
			(end -0.67945 -0.305054)
			(stroke
				(width 0.1)
				(type default)
			)
			(layer "F.Fab")
		)
		(fp_line
			(start -0.12065 0.3048)
			(end -0.67945 0.3048)
			(stroke
				(width 0.1)
				(type default)
			)
			(layer "F.Fab")
		)
		(fp_line
			(start 0.120396 0.3048)
			(end 0.120396 0.2794)
			(stroke
				(width 0.1)
				(type default)
			)
			(layer "F.Fab")
		)
		(fp_line
			(start 0.67945 0.3048)
			(end 0.120396 0.3048)
			(stroke
				(width 0.1)
				(type default)
			)
			(layer "F.Fab")
		)
		(fp_line
			(start -0.12065 0.2794)
			(end -0.12065 0.3048)
			(stroke
				(width 0.1)
				(type default)
			)
			(layer "F.Fab")
		)
		(fp_line
			(start 0.120396 0.2794)
			(end -0.12065 0.2794)
			(stroke
				(width 0.1)
				(type default)
			)
			(layer "F.Fab")
		)
		(fp_line
			(start -0.12065 -0.2794)
			(end 0.12065 -0.2794)
			(stroke
				(width 0.1)
				(type default)
			)
			(layer "F.Fab")
		)
		(fp_line
			(start 0.12065 -0.2794)
			(end 0.12065 -0.3048)
			(stroke
				(width 0.1)
				(type default)
			)
			(layer "F.Fab")
		)
		(fp_line
			(start 0.12065 -0.3048)
			(end 0.67945 -0.3048)
			(stroke
				(width 0.1)
				(type default)
			)
			(layer "F.Fab")
		)
		(fp_line
			(start 0.67945 -0.3048)
			(end 0.67945 0.3048)
			(stroke
				(width 0.1)
				(type default)
			)
			(layer "F.Fab")
		)
		(fp_line
			(start -0.67945 -0.305054)
			(end -0.12065 -0.305054)
			(stroke
				(width 0.1)
				(type default)
			)
			(layer "F.Fab")
		)
		(fp_line
			(start -0.12065 -0.305054)
			(end -0.12065 -0.2794)
			(stroke
				(width 0.1)
				(type default)
			)
			(layer "F.Fab")
		)
		(pad "1" smd circle
			(at -0.40005 0 270)
			(size 0 0)
			(layers "F.Cu" "F.Mask" "F.Paste")
			(net "P2E_BUF2_VDD")
		)
		(pad "2" smd circle
			(at 0.40005 0 270)
			(size 0 0)
			(layers "F.Cu" "F.Mask" "F.Paste")
			(net "GND")
		)
	)
)
